#ISCELL
  mstr_misc dns *
  *
#ISCELL
  pure_quanta quanta_title_block_c *
  *
#ISCELL
  logical_power universal_gnd *
  page129_i100
#CELL
  pure_quanta q_cap *
  page129_i102
#CELL
  pure_quanta q_res *
  page129_i103
#CELL
  pure_quanta q_res *
  page129_i106
#CELL
  pure_quanta q_res *
  page129_i109
#CELL
  pure_quanta q_res *
  page129_i112
#CELL
  pure_quanta q_res *
  page129_i119
#ISCELL
  logical_power universal_power *
  page129_i120
#CELL
  pure_quanta q_res *
  page129_i121
#ISCELL
  logical_power universal_power *
  page129_i122
#CELL
  pure_quanta q_res *
  page129_i123
#ISCELL
  logical_power universal_power *
  page129_i124
#CELL
  pure_quanta q_res *
  page129_i125
#ISCELL
  logical_power universal_power *
  page129_i126
#ISCELL
  standard offpage *
  page129_i22
#CELL
  pure_quanta q_res *
  page129_i26
#ISCELL
  standard offpage *
  page129_i51
#ISCELL
  standard offpage *
  page129_i52
#CELL
  pure_quanta q_res *
  page129_i59
#ISCELL
  standard offpage *
  page129_i64
#ISCELL
  standard offpage *
  page129_i65
#ISCELL
  standard offpage *
  page129_i66
#CELL
  pure_quanta q_res *
  page129_i76
#ISCELL
  standard offpage *
  page129_i83
#CELL
  pure_quanta q_res *
  page129_i86
#ISCELL
  standard offpage *
  page129_i90
#CELL
  pure_quanta q_cap *
  page129_i91
#ISCELL
  logical_power universal_gnd *
  page129_i93
#CELL
  pure_quanta q_cap *
  page129_i94
#ISCELL
  logical_power universal_gnd *
  page129_i96
#ISCELL
  logical_power universal_gnd *
  page129_i97
#CELL
  pure_quanta q_cap *
  page129_i99
